# S9S_MB_2U (Grand Teton) — schematic netlist excerpt (pin names and nets, part order shuffled) for the footprints in the layout excerpt that follows; sources: Cadence DE-HDL packaged netlist, KiCad conversion of 03242023_DA0F0TMBIJ0_F0T_Motherboard_J_brd_V01_OCP.brd

J9  SCONN288_ADR50017P130CC  SCONN288_ADR50017-P130CC IO  pkg DDR288S_1-1VXB  page 90
  VIN_BULK0  = P12V_S3_AUX_CPU0_NVDIMM
  RFU0  = TP_CHE_CPU0_DIMM1_FRU_0
  VIN_MGMT  = P3V3_AUX
  HSCL  = I3C_SPD_DDREFGH_CPU0_LVC1_SCL_R
  HSDA  = I3C_SPD_DDREFGH_CPU0_LVC1_SDA
  VSS0  = GND
  DQ0_A  = M_E_CPU0_SA_DQ<0>
  VSS1  = GND
  DQ1_A  = M_E_CPU0_SA_DQ<1>
  VSS2  = GND
  DQS0_A_T  = M_E_CPU0_SA_DQS_DP<0>
  DQS0_A_C  = M_E_CPU0_SA_DQS_DN<0>
  VSS3  = GND
  DQ4_A  = M_E_CPU0_SA_DQ<4>
  VSS4  = GND
  DQ5_A  = M_E_CPU0_SA_DQ<5>
  VSS5  = GND
  DQ8_A  = M_E_CPU0_SA_DQ<8>
  VSS6  = GND
  DQ9_A  = M_E_CPU0_SA_DQ<9>
  VSS7  = GND
  DQS1_A_T  = M_E_CPU0_SA_DQS_DP<1>
  DQS1_A_C  = M_E_CPU0_SA_DQS_DN<1>
  VSS8  = GND
  DQ12_A  = M_E_CPU0_SA_DQ<12>
  VSS9  = GND
  DQ13_A  = M_E_CPU0_SA_DQ<13>
  VSS10  = GND
  DQ16_A  = M_E_CPU0_SA_DQ<16>
  VSS11  = GND
  DQ17_A  = M_E_CPU0_SA_DQ<17>
  VSS12  = GND
  DQS2_A_T  = M_E_CPU0_SA_DQS_DP<2>
  DQS2_A_C  = M_E_CPU0_SA_DQS_DN<2>
  VSS13  = GND
  DQ20_A  = M_E_CPU0_SA_DQ<20>
  VSS14  = GND
  DQ21_A  = M_E_CPU0_SA_DQ<21>
  VSS15  = GND
  DQ24_A  = M_E_CPU0_SA_DQ<24>
  VSS16  = GND
  DQ25_A  = M_E_CPU0_SA_DQ<25>
  VSS17  = GND
  DQS3_A_T  = M_E_CPU0_SA_DQS_DP<3>
  DQS3_A_C  = M_E_CPU0_SA_DQS_DN<3>
  VSS18  = GND
  DQ28_A  = M_E_CPU0_SA_DQ<28>
  VSS19  = GND
  DQ29_A  = M_E_CPU0_SA_DQ<29>
  VSS20  = GND
  CB0_A  = M_E_CPU0_SA_CB<0>
  VSS21  = GND
  CB1_A  = M_E_CPU0_SA_CB<1>
  VSS22  = GND
  DQS4_A_T  = M_E_CPU0_SA_DQS_DP<4>
  DQS4_A_C  = M_E_CPU0_SA_DQS_DN<4>
  VSS23  = GND
  CB4_A  = M_E_CPU0_SA_CB<4>
  VSS24  = GND
  CB5_A  = M_E_CPU0_SA_CB<5>
  VSS25  = GND
  ALERT_N  = M_E_CPU0_ALERT_N
  VSS26  = GND
  CS0_A_N  = M_E_CPU0_SA_CS_N<0>
  VSS27  = GND
  CA0_A  = M_E_CPU0_SA_CA<0>
  VSS28  = GND
  CA2_A  = M_E_CPU0_SA_CA<2>
  VSS29  = GND
  CA4_A  = M_E_CPU0_SA_CA<4>
  VSS30  = GND
  CA6_A  = M_E_CPU0_SA_CA<6>
  VSS31  = GND
  PAR_A  = M_E_CPU0_SA_PAR
  VSS32  = GND
  CA0_B  = M_E_CPU0_SB_CA<0>
  VSS33  = GND
  CA2_B  = M_E_CPU0_SB_CA<2>
  VSS34  = GND
  CA4_B  = M_E_CPU0_SB_CA<4>
  VSS35  = GND
  CA6_B  = M_E_CPU0_SB_CA<6>
  VSS36  = GND
  CS0_B_N  = M_E_CPU0_SB_CS_N<0>
  VSS37  = GND
  \lbd||rsp_a_n\  = M_E_CPU0_SA_RSP<0>
  \lbs||rsp_b_n\  = M_E_CPU0_SB_RSP<0>
  VSS38  = GND
  CB4_B  = M_E_CPU0_SB_CB<4>
  VSS39  = GND
  CB5_B  = M_E_CPU0_SB_CB<5>
  VSS40  = GND
  \dqs9_b_t||tdqs9_b_t||dbi4_b_n\  = M_E_CPU0_SB_DQS_DP<9>
  \dqs9_b_c||tdqs9_b_c\  = M_E_CPU0_SB_DQS_DN<9>
  VSS41  = GND
  CB0_B  = M_E_CPU0_SB_CB<0>
  VSS42  = GND
  CB1_B  = M_E_CPU0_SB_CB<1>
  VSS43  = GND
  DQ0_B  = M_E_CPU0_SB_DQ<0>
  VSS44  = GND
  DQ1_B  = M_E_CPU0_SB_DQ<1>
  VSS45  = GND
  DQS0_B_T  = M_E_CPU0_SB_DQS_DP<0>
  DQS0_B_C  = M_E_CPU0_SB_DQS_DN<0>
  VSS46  = GND
  DQ4_B  = M_E_CPU0_SB_DQ<4>
  VSS47  = GND
  DQ5_B  = M_E_CPU0_SB_DQ<5>
  VSS48  = GND
  DQ8_B  = M_E_CPU0_SB_DQ<8>
  VSS49  = GND
  DQ9_B  = M_E_CPU0_SB_DQ<9>
  VSS50  = GND
  DQS1_B_T  = M_E_CPU0_SB_DQS_DP<1>
  DQS1_B_C  = M_E_CPU0_SB_DQS_DN<1>
  VSS51  = GND
  DQ12_B  = M_E_CPU0_SB_DQ<12>
  VSS52  = GND
  DQ13_B  = M_E_CPU0_SB_DQ<13>
  VSS53  = GND
  DQ16_B  = M_E_CPU0_SB_DQ<16>
  VSS54  = GND
  DQ17_B  = M_E_CPU0_SB_DQ<17>
  VSS55  = GND
  DQS2_B_T  = M_E_CPU0_SB_DQS_DP<2>
  DQS2_B_C  = M_E_CPU0_SB_DQS_DN<2>
  VSS56  = GND
  DQ20_B  = M_E_CPU0_SB_DQ<20>
  VSS57  = GND
  DQ21_B  = M_E_CPU0_SB_DQ<21>
  VSS58  = GND
  DQ24_B  = M_E_CPU0_SB_DQ<24>
  VSS59  = GND
  DQ25_B  = M_E_CPU0_SB_DQ<25>
  VSS60  = GND
  DQS3_B_T  = M_E_CPU0_SB_DQS_DP<3>
  DQS3_B_C  = M_E_CPU0_SB_DQS_DN<3>
  VSS61  = GND
  DQ28_B  = M_E_CPU0_SB_DQ<28>
  VSS62  = GND
  DQ29_B  = M_E_CPU0_SB_DQ<29>
  VSS63  = GND
  RFU1  = TP_CHE_CPU0_DIMM1_FRU_1
  VIN_BULK1  = P12V_S3_AUX_CPU0_NVDIMM
  VIN_BULK2  = P12V_S3_AUX_CPU0_NVDIMM
  \pwr_good||fail_n\  = PWRGD_CHE_CPU0_DIMM1
  HSA  = PD_CHE_CPU0_DIMM1_SAA
  RFU2  = TP_CHE_CPU0_DIMM1_FRU_2
  RFU3  = TP_CHE_CPU0_DIMM1_FRU_3
  VSS64  = GND
  DQ2_A  = M_E_CPU0_SA_DQ<2>
  VSS65  = GND
  DQ3_A  = M_E_CPU0_SA_DQ<3>
  VSS66  = GND
  \dqs5_a_c||tdqs5_a_c||dqs5_a_t||tdqs5_a_t\  = M_E_CPU0_SA_DQS_DN<5>
  \dqs5_a_t||tdqs5_a_t\  = M_E_CPU0_SA_DQS_DP<5>
  VSS67  = GND
  DQ6_A  = M_E_CPU0_SA_DQ<6>
  VSS68  = GND
  DQ7_A  = M_E_CPU0_SA_DQ<7>
  VSS69  = GND
  DQ10_A  = M_E_CPU0_SA_DQ<10>
  VSS70  = GND
  DQ11_A  = M_E_CPU0_SA_DQ<11>
  VSS71  = GND
  \dqs6_a_c||tdqs6_a_c||dqs6_a_t||tdqs6_a_t\  = M_E_CPU0_SA_DQS_DN<6>
  \dqs6_a_t||tdqs6_a_t\  = M_E_CPU0_SA_DQS_DP<6>
  VSS72  = GND
  DQ14_A  = M_E_CPU0_SA_DQ<14>
  VSS73  = GND
  DQ15_A  = M_E_CPU0_SA_DQ<15>
  VSS74  = GND
  DQ18_A  = M_E_CPU0_SA_DQ<18>
  VSS75  = GND
  DQ19_A  = M_E_CPU0_SA_DQ<19>
  VSS76  = GND
  \dqs7_a_c||tdqs7_a_c\  = M_E_CPU0_SA_DQS_DN<7>
  \dqs7_a_t||tdqs7_a_t\  = M_E_CPU0_SA_DQS_DP<7>
  VSS77  = GND
  DQ22_A  = M_E_CPU0_SA_DQ<22>
  VSS78  = GND
  DQ23_A  = M_E_CPU0_SA_DQ<23>
  VSS79  = GND
  DQ26_A  = M_E_CPU0_SA_DQ<26>
  VSS80  = GND
  DQ27_A  = M_E_CPU0_SA_DQ<27>
  VSS81  = GND
  \dqs8_a_c||tdqs8_a_c\  = M_E_CPU0_SA_DQS_DN<8>
  \dqs8_a_t||tdqs8_a_t\  = M_E_CPU0_SA_DQS_DP<8>
  VSS82  = GND
  DQ30_A  = M_E_CPU0_SA_DQ<30>
  VSS83  = GND
  DQ31_A  = M_E_CPU0_SA_DQ<31>
  VSS84  = GND
  CB2_A  = M_E_CPU0_SA_CB<2>
  VSS85  = GND
  CB3_A  = M_E_CPU0_SA_CB<3>
  VSS86  = GND
  \dqs9_a_c||tdqs9_a_c\  = M_E_CPU0_SA_DQS_DN<9>
  \dqs9_a_t||tdqs9_a_t\  = M_E_CPU0_SA_DQS_DP<9>
  VSS87  = GND
  CB6_A  = M_E_CPU0_SA_CB<6>
  VSS88  = GND
  CB7_A  = M_E_CPU0_SA_CB<7>
  VSS89  = GND
  RESET_N  = RST_M_EF_CPU0_FPGA_N
  VSS90  = GND
  CS1_A_N  = M_E_CPU0_SA_CS_N<1>
  VSS91  = GND
  CA1_A  = M_E_CPU0_SA_CA<1>
  VSS92  = GND
  CA3_A  = M_E_CPU0_SA_CA<3>
  VSS93  = GND
  CA5_A  = M_E_CPU0_SA_CA<5>
  VSS94  = GND
  CK_T  = M_E_CPU0_CLK_DP<0>
  CK_C  = M_E_CPU0_CLK_DN<0>
  VSS95  = GND
  RFU4  = TP_CHE_CPU0_DIMM1_FRU_4
  CA1_B  = M_E_CPU0_SB_CA<1>
  VSS96  = GND
  CA3_B  = M_E_CPU0_SB_CA<3>
  VSS97  = GND
  CA5_B  = M_E_CPU0_SB_CA<5>
  VSS98  = GND
  PAR_B  = M_E_CPU0_SB_PAR
  VSS99  = GND
  CS1_B_N  = M_E_CPU0_SB_CS_N<1>
  VSS100  = GND
  RFU5  = TP_CHE_CPU0_DIMM1_FRU_5
  RFU6  = TP_CHE_CPU0_DIMM1_FRU_6
  VSS101  = GND
  CB6_B  = M_E_CPU0_SB_CB<6>
  VSS102  = GND
  CB7_B  = M_E_CPU0_SB_CB<7>
  VSS103  = GND
  DQS4_B_C  = M_E_CPU0_SB_DQS_DN<4>
  DQS4_B_T  = M_E_CPU0_SB_DQS_DP<4>
  VSS104  = GND
  CB2_B  = M_E_CPU0_SB_CB<2>
  VSS105  = GND
  CB3_B  = M_E_CPU0_SB_CB<3>
  VSS106  = GND
  DQ2_B  = M_E_CPU0_SB_DQ<2>
  VSS107  = GND
  DQ3_B  = M_E_CPU0_SB_DQ<3>
  VSS108  = GND
  \dqs5_b_c||tdqs5_b_c\  = M_E_CPU0_SB_DQS_DN<5>
  \dqs5_b_t||tdqs5_b_t\  = M_E_CPU0_SB_DQS_DP<5>
  VSS109  = GND
  DQ6_B  = M_E_CPU0_SB_DQ<6>
  VSS110  = GND
  DQ7_B  = M_E_CPU0_SB_DQ<7>
  VSS111  = GND
  DQ10_B  = M_E_CPU0_SB_DQ<10>
  VSS112  = GND
  DQ11_B  = M_E_CPU0_SB_DQ<11>
  VSS113  = GND
  \dqs6_b_c||tdqs6_b_c\  = M_E_CPU0_SB_DQS_DN<6>
  \dqs6_b_t||tdqs6_b_t\  = M_E_CPU0_SB_DQS_DP<6>
  VSS114  = GND
  DQ14_B  = M_E_CPU0_SB_DQ<14>
  VSS115  = GND
  DQ15_B  = M_E_CPU0_SB_DQ<15>
  VSS116  = GND
  DQ18_B  = M_E_CPU0_SB_DQ<18>
  VSS117  = GND
  DQ19_B  = M_E_CPU0_SB_DQ<19>
  VSS118  = GND
  \dqs7_b_c||tdqs7_b_c\  = M_E_CPU0_SB_DQS_DN<7>
  \dqs7_b_t||tdqs7_b_t\  = M_E_CPU0_SB_DQS_DP<7>
  VSS119  = GND
  DQ22_B  = M_E_CPU0_SB_DQ<22>
  VSS120  = GND
  DQ23_B  = M_E_CPU0_SB_DQ<23>
  VSS121  = GND
  DQ26_B  = M_E_CPU0_SB_DQ<26>
  VSS122  = GND
  DQ27_B  = M_E_CPU0_SB_DQ<27>
  VSS123  = GND
  \dqs8_b_c||tdqs8_b_c\  = M_E_CPU0_SB_DQS_DN<8>
  \dqs8_b_t||tdqs8_b_t\  = M_E_CPU0_SB_DQS_DP<8>
  VSS124  = GND
  DQ30_B  = M_E_CPU0_SB_DQ<30>
  VSS125  = GND
  DQ31_B  = M_E_CPU0_SB_DQ<31>
  VSS126  = GND
  G1  = GND
  G2  = GND
  G3  = GND

(kicad_pcb
	(version 20260206)
	(generator "pcbnew")
	(generator_version "10.0")
	(general
		(thickness 1.6)
		(legacy_teardrops no)
	)
	(paper "A4")
	(title_block
		(title "03242023_DA0F0TMBIJ0_F0T_Motherboard_J_brd_V01_OCP.brd")
		(comment 1 "Grand Teton / footprint 461 of 6105 (J9), pads 183-228 of 291")
	)
	(layers
		(0 "F.Cu" signal "TOP")
		(4 "In1.Cu" signal "GND")
		(6 "In2.Cu" signal "IN1")
		(8 "In3.Cu" signal "GND1")
		(10 "In4.Cu" signal "IN2")
		(12 "In5.Cu" signal "GND2")
		(14 "In6.Cu" signal "IN3")
		(16 "In7.Cu" signal "GND3")
		(18 "In8.Cu" signal "VCC")
		(20 "In9.Cu" signal "VCC1")
		(22 "In10.Cu" signal "GND4")
		(24 "In11.Cu" signal "IN4")
		(26 "In12.Cu" signal "GND5")
		(28 "In13.Cu" signal "IN5")
		(30 "In14.Cu" signal "GND6")
		(32 "In15.Cu" signal "IN6")
		(34 "In16.Cu" signal "GND7")
		(2 "B.Cu" signal "BOTTOM")
		(9 "F.Adhes" user "F.Adhesive")
		(11 "B.Adhes" user "B.Adhesive")
		(13 "F.Paste" user "Package Geometry/Pastemask Top")
		(15 "B.Paste" user "Package Geometry/Pastemask Bottom")
		(5 "F.SilkS" user "Ref Des/Silkscreen Top")
		(7 "B.SilkS" user "Ref Des/Silkscreen Bottom")
		(1 "F.Mask" user "Board Geometry/Soldermask Top")
		(3 "B.Mask" user "Board Geometry/Soldermask Bottom")
		(17 "Dwgs.User" user "User.Drawings")
		(19 "Cmts.User" user "User.Comments")
		(21 "Eco1.User" user "User.Eco1")
		(23 "Eco2.User" user "User.Eco2")
		(25 "Edge.Cuts" user "Board Geometry/Outline")
		(27 "Margin" user)
		(31 "F.CrtYd" user "Package Geometry/Place Bound Top")
		(29 "B.CrtYd" user "Package Geometry/Place Bound Bottom")
		(35 "F.Fab" user "Ref Des/Assembly Top")
		(33 "B.Fab" user "Ref Des/Assembly Bottom")
	)
	(footprint ""
		(layer "F.Cu")
		(at 416.347148 -258.091686)
		(property "Reference" "J9"
			(at -3.683 -81.702148 0)
			(unlocked yes)
			(layer "F.SilkS")
			(effects
				(font
					(size 0.7874 0.5842)
					(thickness 0.1524)
				)
				(justify left)
			)
		)
		(property "Value" ""
			(at 0 0 0)
			(layer "F.Fab")
			(effects
				(font
					(size 1.27 1.27)
				)
			)
		)
		(duplicate_pad_numbers_are_jumpers no)
		(pad "183" smd rect
			(at 2.050034 -31.025084 270)
			(size 0.519938 1.4986)
			(layers "F.Cu" "F.Mask" "F.Paste")
			(net "M_E_CPU0_SA_DQ<23>")
		)
		(pad "184" smd rect
			(at 2.050034 -30.174946 270)
			(size 0.519938 1.4986)
			(layers "F.Cu" "F.Mask" "F.Paste")
			(net "GND")
		)
		(pad "185" smd rect
			(at 2.050034 -29.325062 270)
			(size 0.519938 1.4986)
			(layers "F.Cu" "F.Mask" "F.Paste")
			(net "M_E_CPU0_SA_DQ<26>")
		)
		(pad "186" smd rect
			(at 2.050034 -28.474924 270)
			(size 0.519938 1.4986)
			(layers "F.Cu" "F.Mask" "F.Paste")
			(net "GND")
		)
		(pad "187" smd rect
			(at 2.050034 -27.62504 270)
			(size 0.519938 1.4986)
			(layers "F.Cu" "F.Mask" "F.Paste")
			(net "M_E_CPU0_SA_DQ<27>")
		)
		(pad "188" smd rect
			(at 2.050034 -26.774902 270)
			(size 0.519938 1.4986)
			(layers "F.Cu" "F.Mask" "F.Paste")
			(net "GND")
		)
		(pad "189" smd rect
			(at 2.050034 -25.925018 270)
			(size 0.519938 1.4986)
			(layers "F.Cu" "F.Mask" "F.Paste")
			(net "M_E_CPU0_SA_DQS_DN<8>")
		)
		(pad "190" smd rect
			(at 2.050034 -25.07488 270)
			(size 0.519938 1.4986)
			(layers "F.Cu" "F.Mask" "F.Paste")
			(net "M_E_CPU0_SA_DQS_DP<8>")
		)
		(pad "191" smd rect
			(at 2.050034 -24.224996 270)
			(size 0.519938 1.4986)
			(layers "F.Cu" "F.Mask" "F.Paste")
			(net "GND")
		)
		(pad "192" smd rect
			(at 2.050034 -23.375112 270)
			(size 0.519938 1.4986)
			(layers "F.Cu" "F.Mask" "F.Paste")
			(net "M_E_CPU0_SA_DQ<30>")
		)
		(pad "193" smd rect
			(at 2.050034 -22.524974 270)
			(size 0.519938 1.4986)
			(layers "F.Cu" "F.Mask" "F.Paste")
			(net "GND")
		)
		(pad "194" smd rect
			(at 2.050034 -21.67509 270)
			(size 0.519938 1.4986)
			(layers "F.Cu" "F.Mask" "F.Paste")
			(net "M_E_CPU0_SA_DQ<31>")
		)
		(pad "195" smd rect
			(at 2.050034 -20.824952 270)
			(size 0.519938 1.4986)
			(layers "F.Cu" "F.Mask" "F.Paste")
			(net "GND")
		)
		(pad "196" smd rect
			(at 2.050034 -19.975068 270)
			(size 0.519938 1.4986)
			(layers "F.Cu" "F.Mask" "F.Paste")
			(net "M_E_CPU0_SA_CB<2>")
		)
		(pad "197" smd rect
			(at 2.050034 -19.12493 270)
			(size 0.519938 1.4986)
			(layers "F.Cu" "F.Mask" "F.Paste")
			(net "GND")
		)
		(pad "198" smd rect
			(at 2.050034 -18.275046 270)
			(size 0.519938 1.4986)
			(layers "F.Cu" "F.Mask" "F.Paste")
			(net "M_E_CPU0_SA_CB<3>")
		)
		(pad "199" smd rect
			(at 2.050034 -17.424908 270)
			(size 0.519938 1.4986)
			(layers "F.Cu" "F.Mask" "F.Paste")
			(net "GND")
		)
		(pad "200" smd rect
			(at 2.050034 -16.575024 270)
			(size 0.519938 1.4986)
			(layers "F.Cu" "F.Mask" "F.Paste")
			(net "M_E_CPU0_SA_DQS_DN<9>")
		)
		(pad "201" smd rect
			(at 2.050034 -15.724886 270)
			(size 0.519938 1.4986)
			(layers "F.Cu" "F.Mask" "F.Paste")
			(net "M_E_CPU0_SA_DQS_DP<9>")
		)
		(pad "202" smd rect
			(at 2.050034 -14.875002 270)
			(size 0.519938 1.4986)
			(layers "F.Cu" "F.Mask" "F.Paste")
			(net "GND")
		)
		(pad "203" smd rect
			(at 2.050034 -14.025118 270)
			(size 0.519938 1.4986)
			(layers "F.Cu" "F.Mask" "F.Paste")
			(net "M_E_CPU0_SA_CB<6>")
		)
		(pad "204" smd rect
			(at 2.050034 -13.17498 270)
			(size 0.519938 1.4986)
			(layers "F.Cu" "F.Mask" "F.Paste")
			(net "GND")
		)
		(pad "205" smd rect
			(at 2.050034 -12.325096 270)
			(size 0.519938 1.4986)
			(layers "F.Cu" "F.Mask" "F.Paste")
			(net "M_E_CPU0_SA_CB<7>")
		)
		(pad "206" smd rect
			(at 2.050034 -11.474958 270)
			(size 0.519938 1.4986)
			(layers "F.Cu" "F.Mask" "F.Paste")
			(net "GND")
		)
		(pad "207" smd rect
			(at 2.050034 -10.625074 270)
			(size 0.519938 1.4986)
			(layers "F.Cu" "F.Mask" "F.Paste")
			(net "RST_M_EF_CPU0_FPGA_N")
		)
		(pad "208" smd rect
			(at 2.050034 -9.774936 270)
			(size 0.519938 1.4986)
			(layers "F.Cu" "F.Mask" "F.Paste")
			(net "GND")
		)
		(pad "209" smd rect
			(at 2.050034 -8.925052 270)
			(size 0.519938 1.4986)
			(layers "F.Cu" "F.Mask" "F.Paste")
			(net "M_E_CPU0_SA_CS_N<1>")
		)
		(pad "210" smd rect
			(at 2.050034 -8.074914 270)
			(size 0.519938 1.4986)
			(layers "F.Cu" "F.Mask" "F.Paste")
			(net "GND")
		)
		(pad "211" smd rect
			(at 2.050034 -7.22503 270)
			(size 0.519938 1.4986)
			(layers "F.Cu" "F.Mask" "F.Paste")
			(net "M_E_CPU0_SA_CA<1>")
		)
		(pad "212" smd rect
			(at 2.050034 -6.374892 270)
			(size 0.519938 1.4986)
			(layers "F.Cu" "F.Mask" "F.Paste")
			(net "GND")
		)
		(pad "213" smd rect
			(at 2.050034 -5.525008 270)
			(size 0.519938 1.4986)
			(layers "F.Cu" "F.Mask" "F.Paste")
			(net "M_E_CPU0_SA_CA<3>")
		)
		(pad "214" smd rect
			(at 2.050034 -4.675124 270)
			(size 0.519938 1.4986)
			(layers "F.Cu" "F.Mask" "F.Paste")
			(net "GND")
		)
		(pad "215" smd rect
			(at 2.050034 -3.824986 270)
			(size 0.519938 1.4986)
			(layers "F.Cu" "F.Mask" "F.Paste")
			(net "M_E_CPU0_SA_CA<5>")
		)
		(pad "216" smd rect
			(at 2.050034 -2.975102 270)
			(size 0.519938 1.4986)
			(layers "F.Cu" "F.Mask" "F.Paste")
			(net "GND")
		)
		(pad "217" smd rect
			(at 2.050034 -2.124964 270)
			(size 0.519938 1.4986)
			(layers "F.Cu" "F.Mask" "F.Paste")
			(net "M_E_CPU0_CLK_DP<0>")
		)
		(pad "218" smd rect
			(at 2.050034 -1.27508 270)
			(size 0.519938 1.4986)
			(layers "F.Cu" "F.Mask" "F.Paste")
			(net "M_E_CPU0_CLK_DN<0>")
		)
		(pad "219" smd rect
			(at 2.050034 -0.424942 270)
			(size 0.519938 1.4986)
			(layers "F.Cu" "F.Mask" "F.Paste")
			(net "GND")
		)
		(pad "220" smd rect
			(at 2.050034 5.525008 270)
			(size 0.519938 1.4986)
			(layers "F.Cu" "F.Mask" "F.Paste")
			(net "TP_CHE_CPU0_DIMM1_FRU_4")
		)
		(pad "221" smd rect
			(at 2.050034 6.374892 270)
			(size 0.519938 1.4986)
			(layers "F.Cu" "F.Mask" "F.Paste")
			(net "M_E_CPU0_SB_CA<1>")
		)
		(pad "222" smd rect
			(at 2.050034 7.22503 270)
			(size 0.519938 1.4986)
			(layers "F.Cu" "F.Mask" "F.Paste")
			(net "GND")
		)
		(pad "223" smd rect
			(at 2.050034 8.074914 270)
			(size 0.519938 1.4986)
			(layers "F.Cu" "F.Mask" "F.Paste")
			(net "M_E_CPU0_SB_CA<3>")
		)
		(pad "224" smd rect
			(at 2.050034 8.925052 270)
			(size 0.519938 1.4986)
			(layers "F.Cu" "F.Mask" "F.Paste")
			(net "GND")
		)
		(pad "225" smd rect
			(at 2.050034 9.774936 270)
			(size 0.519938 1.4986)
			(layers "F.Cu" "F.Mask" "F.Paste")
			(net "M_E_CPU0_SB_CA<5>")
		)
		(pad "226" smd rect
			(at 2.050034 10.625074 270)
			(size 0.519938 1.4986)
			(layers "F.Cu" "F.Mask" "F.Paste")
			(net "GND")
		)
		(pad "227" smd rect
			(at 2.050034 11.474958 270)
			(size 0.519938 1.4986)
			(layers "F.Cu" "F.Mask" "F.Paste")
			(net "M_E_CPU0_SB_PAR")
		)
		(pad "228" smd rect
			(at 2.050034 12.325096 270)
			(size 0.519938 1.4986)
			(layers "F.Cu" "F.Mask" "F.Paste")
			(net "GND")
		)
	)
)
